FILE_TYPE = CONNECTIVITY;
{Allegro Design Entry HDL 16.6-p007 (v16-6-112F) 10/10/2012}
"PAGE_NUMBER" = 179;
0"NC";
END.
